(kicad_pcb
	(version 20260206)
	(generator "pcbnew")
	(generator_version "10.0")
	(general
		(thickness 1.6)
		(legacy_teardrops no)
	)
	(paper "A4")
	(title_block
		(title "03242023_DA0F0TMBIJ0_F0T_Motherboard_J_brd_V01_OCP.brd")
		(comment 1 "Grand Teton / footprint 1335 of 6105 (J17), pads 1-112 of 291")
	)
	(layers
		(0 "F.Cu" signal "TOP")
		(4 "In1.Cu" signal "GND")
		(6 "In2.Cu" signal "IN1")
		(8 "In3.Cu" signal "GND1")
		(10 "In4.Cu" signal "IN2")
		(12 "In5.Cu" signal "GND2")
		(14 "In6.Cu" signal "IN3")
		(16 "In7.Cu" signal "GND3")
		(18 "In8.Cu" signal "VCC")
		(20 "In9.Cu" signal "VCC1")
		(22 "In10.Cu" signal "GND4")
		(24 "In11.Cu" signal "IN4")
		(26 "In12.Cu" signal "GND5")
		(28 "In13.Cu" signal "IN5")
		(30 "In14.Cu" signal "GND6")
		(32 "In15.Cu" signal "IN6")
		(34 "In16.Cu" signal "GND7")
		(2 "B.Cu" signal "BOTTOM")
		(9 "F.Adhes" user "F.Adhesive")
		(11 "B.Adhes" user "B.Adhesive")
		(13 "F.Paste" user "Package Geometry/Pastemask Top")
		(15 "B.Paste" user "Package Geometry/Pastemask Bottom")
		(5 "F.SilkS" user "Ref Des/Silkscreen Top")
		(7 "B.SilkS" user "Ref Des/Silkscreen Bottom")
		(1 "F.Mask" user "Board Geometry/Soldermask Top")
		(3 "B.Mask" user "Board Geometry/Soldermask Bottom")
		(17 "Dwgs.User" user "User.Drawings")
		(19 "Cmts.User" user "User.Comments")
		(21 "Eco1.User" user "User.Eco1")
		(23 "Eco2.User" user "User.Eco2")
		(25 "Edge.Cuts" user "Board Geometry/Outline")
		(27 "Margin" user)
		(31 "F.CrtYd" user "Package Geometry/Place Bound Top")
		(29 "B.CrtYd" user "Package Geometry/Place Bound Bottom")
		(35 "F.Fab" user "Ref Des/Assembly Top")
		(33 "B.Fab" user "Ref Des/Assembly Bottom")
	)
	(footprint ""
		(layer "F.Cu")
		(at 55.45328 -258.091686)
		(property "Reference" "J17"
			(at -0.178562 -81.717134 0)
			(unlocked yes)
			(layer "F.SilkS")
			(effects
				(font
					(size 0.7874 0.5842)
					(thickness 0.1524)
				)
				(justify left)
			)
		)
		(property "Value" ""
			(at 0 0 0)
			(layer "F.Fab")
			(effects
				(font
					(size 1.27 1.27)
				)
			)
		)
		(duplicate_pad_numbers_are_jumpers no)
		(pad "1" smd rect
			(at -2.050034 -63.324994 270)
			(size 0.519938 1.4986)
			(layers "F.Cu" "F.Mask" "F.Paste")
			(net "P12V_S3_AUX_CPU1_NVDIMM")
		)
		(pad "2" smd rect
			(at -2.050034 -62.47511 270)
			(size 0.519938 1.4986)
			(layers "F.Cu" "F.Mask" "F.Paste")
			(net "TP_CHA_CPU1_DIMM1_FRU_0")
		)
		(pad "3" smd rect
			(at -2.050034 -61.624972 270)
			(size 0.519938 1.4986)
			(layers "F.Cu" "F.Mask" "F.Paste")
			(net "P3V3_AUX")
		)
		(pad "4" smd rect
			(at -2.050034 -60.775088 270)
			(size 0.519938 1.4986)
			(layers "F.Cu" "F.Mask" "F.Paste")
			(net "I3C_SPD_DDRABCD_CPU1_LVC1_SCL_R")
		)
		(pad "5" smd rect
			(at -2.050034 -59.92495 270)
			(size 0.519938 1.4986)
			(layers "F.Cu" "F.Mask" "F.Paste")
			(net "I3C_SPD_DDRABCD_CPU1_LVC1_SDA")
		)
		(pad "6" smd rect
			(at -2.050034 -59.075066 270)
			(size 0.519938 1.4986)
			(layers "F.Cu" "F.Mask" "F.Paste")
			(net "GND")
		)
		(pad "7" smd rect
			(at -2.050034 -58.224928 270)
			(size 0.519938 1.4986)
			(layers "F.Cu" "F.Mask" "F.Paste")
			(net "M_A_CPU1_SA_DQ<0>")
		)
		(pad "8" smd rect
			(at -2.050034 -57.375044 270)
			(size 0.519938 1.4986)
			(layers "F.Cu" "F.Mask" "F.Paste")
			(net "GND")
		)
		(pad "9" smd rect
			(at -2.050034 -56.524906 270)
			(size 0.519938 1.4986)
			(layers "F.Cu" "F.Mask" "F.Paste")
			(net "M_A_CPU1_SA_DQ<1>")
		)
		(pad "10" smd rect
			(at -2.050034 -55.675022 270)
			(size 0.519938 1.4986)
			(layers "F.Cu" "F.Mask" "F.Paste")
			(net "GND")
		)
		(pad "11" smd rect
			(at -2.050034 -54.824884 270)
			(size 0.519938 1.4986)
			(layers "F.Cu" "F.Mask" "F.Paste")
			(net "M_A_CPU1_SA_DQS_DP<0>")
		)
		(pad "12" smd rect
			(at -2.050034 -53.975 270)
			(size 0.519938 1.4986)
			(layers "F.Cu" "F.Mask" "F.Paste")
			(net "M_A_CPU1_SA_DQS_DN<0>")
		)
		(pad "13" smd rect
			(at -2.050034 -53.125116 270)
			(size 0.519938 1.4986)
			(layers "F.Cu" "F.Mask" "F.Paste")
			(net "GND")
		)
		(pad "14" smd rect
			(at -2.050034 -52.274978 270)
			(size 0.519938 1.4986)
			(layers "F.Cu" "F.Mask" "F.Paste")
			(net "M_A_CPU1_SA_DQ<4>")
		)
		(pad "15" smd rect
			(at -2.050034 -51.425094 270)
			(size 0.519938 1.4986)
			(layers "F.Cu" "F.Mask" "F.Paste")
			(net "GND")
		)
		(pad "16" smd rect
			(at -2.050034 -50.574956 270)
			(size 0.519938 1.4986)
			(layers "F.Cu" "F.Mask" "F.Paste")
			(net "M_A_CPU1_SA_DQ<5>")
		)
		(pad "17" smd rect
			(at -2.050034 -49.725072 270)
			(size 0.519938 1.4986)
			(layers "F.Cu" "F.Mask" "F.Paste")
			(net "GND")
		)
		(pad "18" smd rect
			(at -2.050034 -48.874934 270)
			(size 0.519938 1.4986)
			(layers "F.Cu" "F.Mask" "F.Paste")
			(net "M_A_CPU1_SA_DQ<8>")
		)
		(pad "19" smd rect
			(at -2.050034 -48.02505 270)
			(size 0.519938 1.4986)
			(layers "F.Cu" "F.Mask" "F.Paste")
			(net "GND")
		)
		(pad "20" smd rect
			(at -2.050034 -47.174912 270)
			(size 0.519938 1.4986)
			(layers "F.Cu" "F.Mask" "F.Paste")
			(net "M_A_CPU1_SA_DQ<9>")
		)
		(pad "21" smd rect
			(at -2.050034 -46.325028 270)
			(size 0.519938 1.4986)
			(layers "F.Cu" "F.Mask" "F.Paste")
			(net "GND")
		)
		(pad "22" smd rect
			(at -2.050034 -45.47489 270)
			(size 0.519938 1.4986)
			(layers "F.Cu" "F.Mask" "F.Paste")
			(net "M_A_CPU1_SA_DQS_DP<1>")
		)
		(pad "23" smd rect
			(at -2.050034 -44.625006 270)
			(size 0.519938 1.4986)
			(layers "F.Cu" "F.Mask" "F.Paste")
			(net "M_A_CPU1_SA_DQS_DN<1>")
		)
		(pad "24" smd rect
			(at -2.050034 -43.775122 270)
			(size 0.519938 1.4986)
			(layers "F.Cu" "F.Mask" "F.Paste")
			(net "GND")
		)
		(pad "25" smd rect
			(at -2.050034 -42.924984 270)
			(size 0.519938 1.4986)
			(layers "F.Cu" "F.Mask" "F.Paste")
			(net "M_A_CPU1_SA_DQ<12>")
		)
		(pad "26" smd rect
			(at -2.050034 -42.0751 270)
			(size 0.519938 1.4986)
			(layers "F.Cu" "F.Mask" "F.Paste")
			(net "GND")
		)
		(pad "27" smd rect
			(at -2.050034 -41.224962 270)
			(size 0.519938 1.4986)
			(layers "F.Cu" "F.Mask" "F.Paste")
			(net "M_A_CPU1_SA_DQ<13>")
		)
		(pad "28" smd rect
			(at -2.050034 -40.375078 270)
			(size 0.519938 1.4986)
			(layers "F.Cu" "F.Mask" "F.Paste")
			(net "GND")
		)
		(pad "29" smd rect
			(at -2.050034 -39.52494 270)
			(size 0.519938 1.4986)
			(layers "F.Cu" "F.Mask" "F.Paste")
			(net "M_A_CPU1_SA_DQ<16>")
		)
		(pad "30" smd rect
			(at -2.050034 -38.675056 270)
			(size 0.519938 1.4986)
			(layers "F.Cu" "F.Mask" "F.Paste")
			(net "GND")
		)
		(pad "31" smd rect
			(at -2.050034 -37.824918 270)
			(size 0.519938 1.4986)
			(layers "F.Cu" "F.Mask" "F.Paste")
			(net "M_A_CPU1_SA_DQ<17>")
		)
		(pad "32" smd rect
			(at -2.050034 -36.975034 270)
			(size 0.519938 1.4986)
			(layers "F.Cu" "F.Mask" "F.Paste")
			(net "GND")
		)
		(pad "33" smd rect
			(at -2.050034 -36.124896 270)
			(size 0.519938 1.4986)
			(layers "F.Cu" "F.Mask" "F.Paste")
			(net "M_A_CPU1_SA_DQS_DP<2>")
		)
		(pad "34" smd rect
			(at -2.050034 -35.275012 270)
			(size 0.519938 1.4986)
			(layers "F.Cu" "F.Mask" "F.Paste")
			(net "M_A_CPU1_SA_DQS_DN<2>")
		)
		(pad "35" smd rect
			(at -2.050034 -34.425128 270)
			(size 0.519938 1.4986)
			(layers "F.Cu" "F.Mask" "F.Paste")
			(net "GND")
		)
		(pad "36" smd rect
			(at -2.050034 -33.57499 270)
			(size 0.519938 1.4986)
			(layers "F.Cu" "F.Mask" "F.Paste")
			(net "M_A_CPU1_SA_DQ<20>")
		)
		(pad "37" smd rect
			(at -2.050034 -32.725106 270)
			(size 0.519938 1.4986)
			(layers "F.Cu" "F.Mask" "F.Paste")
			(net "GND")
		)
		(pad "38" smd rect
			(at -2.050034 -31.874968 270)
			(size 0.519938 1.4986)
			(layers "F.Cu" "F.Mask" "F.Paste")
			(net "M_A_CPU1_SA_DQ<21>")
		)
		(pad "39" smd rect
			(at -2.050034 -31.025084 270)
			(size 0.519938 1.4986)
			(layers "F.Cu" "F.Mask" "F.Paste")
			(net "GND")
		)
		(pad "40" smd rect
			(at -2.050034 -30.174946 270)
			(size 0.519938 1.4986)
			(layers "F.Cu" "F.Mask" "F.Paste")
			(net "M_A_CPU1_SA_DQ<24>")
		)
		(pad "41" smd rect
			(at -2.050034 -29.325062 270)
			(size 0.519938 1.4986)
			(layers "F.Cu" "F.Mask" "F.Paste")
			(net "GND")
		)
		(pad "42" smd rect
			(at -2.050034 -28.474924 270)
			(size 0.519938 1.4986)
			(layers "F.Cu" "F.Mask" "F.Paste")
			(net "M_A_CPU1_SA_DQ<25>")
		)
		(pad "43" smd rect
			(at -2.050034 -27.62504 270)
			(size 0.519938 1.4986)
			(layers "F.Cu" "F.Mask" "F.Paste")
			(net "GND")
		)
		(pad "44" smd rect
			(at -2.050034 -26.774902 270)
			(size 0.519938 1.4986)
			(layers "F.Cu" "F.Mask" "F.Paste")
			(net "M_A_CPU1_SA_DQS_DP<3>")
		)
		(pad "45" smd rect
			(at -2.050034 -25.925018 270)
			(size 0.519938 1.4986)
			(layers "F.Cu" "F.Mask" "F.Paste")
			(net "M_A_CPU1_SA_DQS_DN<3>")
		)
		(pad "46" smd rect
			(at -2.050034 -25.07488 270)
			(size 0.519938 1.4986)
			(layers "F.Cu" "F.Mask" "F.Paste")
			(net "GND")
		)
		(pad "47" smd rect
			(at -2.050034 -24.224996 270)
			(size 0.519938 1.4986)
			(layers "F.Cu" "F.Mask" "F.Paste")
			(net "M_A_CPU1_SA_DQ<28>")
		)
		(pad "48" smd rect
			(at -2.050034 -23.375112 270)
			(size 0.519938 1.4986)
			(layers "F.Cu" "F.Mask" "F.Paste")
			(net "GND")
		)
		(pad "49" smd rect
			(at -2.050034 -22.524974 270)
			(size 0.519938 1.4986)
			(layers "F.Cu" "F.Mask" "F.Paste")
			(net "M_A_CPU1_SA_DQ<29>")
		)
		(pad "50" smd rect
			(at -2.050034 -21.67509 270)
			(size 0.519938 1.4986)
			(layers "F.Cu" "F.Mask" "F.Paste")
			(net "GND")
		)
		(pad "51" smd rect
			(at -2.050034 -20.824952 270)
			(size 0.519938 1.4986)
			(layers "F.Cu" "F.Mask" "F.Paste")
			(net "M_A_CPU1_SA_CB<0>")
		)
		(pad "52" smd rect
			(at -2.050034 -19.975068 270)
			(size 0.519938 1.4986)
			(layers "F.Cu" "F.Mask" "F.Paste")
			(net "GND")
		)
		(pad "53" smd rect
			(at -2.050034 -19.12493 270)
			(size 0.519938 1.4986)
			(layers "F.Cu" "F.Mask" "F.Paste")
			(net "M_A_CPU1_SA_CB<1>")
		)
		(pad "54" smd rect
			(at -2.050034 -18.275046 270)
			(size 0.519938 1.4986)
			(layers "F.Cu" "F.Mask" "F.Paste")
			(net "GND")
		)
		(pad "55" smd rect
			(at -2.050034 -17.424908 270)
			(size 0.519938 1.4986)
			(layers "F.Cu" "F.Mask" "F.Paste")
			(net "M_A_CPU1_SA_DQS_DP<4>")
		)
		(pad "56" smd rect
			(at -2.050034 -16.575024 270)
			(size 0.519938 1.4986)
			(layers "F.Cu" "F.Mask" "F.Paste")
			(net "M_A_CPU1_SA_DQS_DN<4>")
		)
		(pad "57" smd rect
			(at -2.050034 -15.724886 270)
			(size 0.519938 1.4986)
			(layers "F.Cu" "F.Mask" "F.Paste")
			(net "GND")
		)
		(pad "58" smd rect
			(at -2.050034 -14.875002 270)
			(size 0.519938 1.4986)
			(layers "F.Cu" "F.Mask" "F.Paste")
			(net "M_A_CPU1_SA_CB<4>")
		)
		(pad "59" smd rect
			(at -2.050034 -14.025118 270)
			(size 0.519938 1.4986)
			(layers "F.Cu" "F.Mask" "F.Paste")
			(net "GND")
		)
		(pad "60" smd rect
			(at -2.050034 -13.17498 270)
			(size 0.519938 1.4986)
			(layers "F.Cu" "F.Mask" "F.Paste")
			(net "M_A_CPU1_SA_CB<5>")
		)
		(pad "61" smd rect
			(at -2.050034 -12.325096 270)
			(size 0.519938 1.4986)
			(layers "F.Cu" "F.Mask" "F.Paste")
			(net "GND")
		)
		(pad "62" smd rect
			(at -2.050034 -11.474958 270)
			(size 0.519938 1.4986)
			(layers "F.Cu" "F.Mask" "F.Paste")
			(net "M_A_CPU1_ALERT_N")
		)
		(pad "63" smd rect
			(at -2.050034 -10.625074 270)
			(size 0.519938 1.4986)
			(layers "F.Cu" "F.Mask" "F.Paste")
			(net "GND")
		)
		(pad "64" smd rect
			(at -2.050034 -9.774936 270)
			(size 0.519938 1.4986)
			(layers "F.Cu" "F.Mask" "F.Paste")
			(net "M_A_CPU1_SA_CS_N<0>")
		)
		(pad "65" smd rect
			(at -2.050034 -8.925052 270)
			(size 0.519938 1.4986)
			(layers "F.Cu" "F.Mask" "F.Paste")
			(net "GND")
		)
		(pad "66" smd rect
			(at -2.050034 -8.074914 270)
			(size 0.519938 1.4986)
			(layers "F.Cu" "F.Mask" "F.Paste")
			(net "M_A_CPU1_SA_CA<0>")
		)
		(pad "67" smd rect
			(at -2.050034 -7.22503 270)
			(size 0.519938 1.4986)
			(layers "F.Cu" "F.Mask" "F.Paste")
			(net "GND")
		)
		(pad "68" smd rect
			(at -2.050034 -6.374892 270)
			(size 0.519938 1.4986)
			(layers "F.Cu" "F.Mask" "F.Paste")
			(net "M_A_CPU1_SA_CA<2>")
		)
		(pad "69" smd rect
			(at -2.050034 -5.525008 270)
			(size 0.519938 1.4986)
			(layers "F.Cu" "F.Mask" "F.Paste")
			(net "GND")
		)
		(pad "70" smd rect
			(at -2.050034 -4.675124 270)
			(size 0.519938 1.4986)
			(layers "F.Cu" "F.Mask" "F.Paste")
			(net "M_A_CPU1_SA_CA<4>")
		)
		(pad "71" smd rect
			(at -2.050034 -3.824986 270)
			(size 0.519938 1.4986)
			(layers "F.Cu" "F.Mask" "F.Paste")
			(net "GND")
		)
		(pad "72" smd rect
			(at -2.050034 -2.975102 270)
			(size 0.519938 1.4986)
			(layers "F.Cu" "F.Mask" "F.Paste")
			(net "M_A_CPU1_SA_CA<6>")
		)
		(pad "73" smd rect
			(at -2.050034 -2.124964 270)
			(size 0.519938 1.4986)
			(layers "F.Cu" "F.Mask" "F.Paste")
			(net "GND")
		)
		(pad "74" smd rect
			(at -2.050034 -1.27508 270)
			(size 0.519938 1.4986)
			(layers "F.Cu" "F.Mask" "F.Paste")
			(net "M_A_CPU1_SA_PAR")
		)
		(pad "75" smd rect
			(at -2.050034 -0.424942 270)
			(size 0.519938 1.4986)
			(layers "F.Cu" "F.Mask" "F.Paste")
			(net "GND")
		)
		(pad "76" smd rect
			(at -2.050034 5.525008 270)
			(size 0.519938 1.4986)
			(layers "F.Cu" "F.Mask" "F.Paste")
			(net "M_A_CPU1_SB_CA<0>")
		)
		(pad "77" smd rect
			(at -2.050034 6.374892 270)
			(size 0.519938 1.4986)
			(layers "F.Cu" "F.Mask" "F.Paste")
			(net "GND")
		)
		(pad "78" smd rect
			(at -2.050034 7.22503 270)
			(size 0.519938 1.4986)
			(layers "F.Cu" "F.Mask" "F.Paste")
			(net "M_A_CPU1_SB_CA<2>")
		)
		(pad "79" smd rect
			(at -2.050034 8.074914 270)
			(size 0.519938 1.4986)
			(layers "F.Cu" "F.Mask" "F.Paste")
			(net "GND")
		)
		(pad "80" smd rect
			(at -2.050034 8.925052 270)
			(size 0.519938 1.4986)
			(layers "F.Cu" "F.Mask" "F.Paste")
			(net "M_A_CPU1_SB_CA<4>")
		)
		(pad "81" smd rect
			(at -2.050034 9.774936 270)
			(size 0.519938 1.4986)
			(layers "F.Cu" "F.Mask" "F.Paste")
			(net "GND")
		)
		(pad "82" smd rect
			(at -2.050034 10.625074 270)
			(size 0.519938 1.4986)
			(layers "F.Cu" "F.Mask" "F.Paste")
			(net "M_A_CPU1_SB_CA<6>")
		)
		(pad "83" smd rect
			(at -2.050034 11.474958 270)
			(size 0.519938 1.4986)
			(layers "F.Cu" "F.Mask" "F.Paste")
			(net "GND")
		)
		(pad "84" smd rect
			(at -2.050034 12.325096 270)
			(size 0.519938 1.4986)
			(layers "F.Cu" "F.Mask" "F.Paste")
			(net "M_A_CPU1_SB_CS_N<0>")
		)
		(pad "85" smd rect
			(at -2.050034 13.17498 270)
			(size 0.519938 1.4986)
			(layers "F.Cu" "F.Mask" "F.Paste")
			(net "GND")
		)
		(pad "86" smd rect
			(at -2.050034 14.025118 270)
			(size 0.519938 1.4986)
			(layers "F.Cu" "F.Mask" "F.Paste")
			(net "M_A_CPU1_SA_RSP<0>")
		)
		(pad "87" smd rect
			(at -2.050034 14.875002 270)
			(size 0.519938 1.4986)
			(layers "F.Cu" "F.Mask" "F.Paste")
			(net "M_A_CPU1_SB_RSP<0>")
		)
		(pad "88" smd rect
			(at -2.050034 15.724886 270)
			(size 0.519938 1.4986)
			(layers "F.Cu" "F.Mask" "F.Paste")
			(net "GND")
		)
		(pad "89" smd rect
			(at -2.050034 16.575024 270)
			(size 0.519938 1.4986)
			(layers "F.Cu" "F.Mask" "F.Paste")
			(net "M_A_CPU1_SB_CB<4>")
		)
		(pad "90" smd rect
			(at -2.050034 17.424908 270)
			(size 0.519938 1.4986)
			(layers "F.Cu" "F.Mask" "F.Paste")
			(net "GND")
		)
		(pad "91" smd rect
			(at -2.050034 18.275046 270)
			(size 0.519938 1.4986)
			(layers "F.Cu" "F.Mask" "F.Paste")
			(net "M_A_CPU1_SB_CB<5>")
		)
		(pad "92" smd rect
			(at -2.050034 19.12493 270)
			(size 0.519938 1.4986)
			(layers "F.Cu" "F.Mask" "F.Paste")
			(net "GND")
		)
		(pad "93" smd rect
			(at -2.050034 19.975068 270)
			(size 0.519938 1.4986)
			(layers "F.Cu" "F.Mask" "F.Paste")
			(net "M_A_CPU1_SB_DQS_DP<9>")
		)
		(pad "94" smd rect
			(at -2.050034 20.824952 270)
			(size 0.519938 1.4986)
			(layers "F.Cu" "F.Mask" "F.Paste")
			(net "M_A_CPU1_SB_DQS_DN<9>")
		)
		(pad "95" smd rect
			(at -2.050034 21.67509 270)
			(size 0.519938 1.4986)
			(layers "F.Cu" "F.Mask" "F.Paste")
			(net "GND")
		)
		(pad "96" smd rect
			(at -2.050034 22.524974 270)
			(size 0.519938 1.4986)
			(layers "F.Cu" "F.Mask" "F.Paste")
			(net "M_A_CPU1_SB_CB<0>")
		)
		(pad "97" smd rect
			(at -2.050034 23.375112 270)
			(size 0.519938 1.4986)
			(layers "F.Cu" "F.Mask" "F.Paste")
			(net "GND")
		)
		(pad "98" smd rect
			(at -2.050034 24.224996 270)
			(size 0.519938 1.4986)
			(layers "F.Cu" "F.Mask" "F.Paste")
			(net "M_A_CPU1_SB_CB<1>")
		)
		(pad "99" smd rect
			(at -2.050034 25.07488 270)
			(size 0.519938 1.4986)
			(layers "F.Cu" "F.Mask" "F.Paste")
			(net "GND")
		)
		(pad "100" smd rect
			(at -2.050034 25.925018 270)
			(size 0.519938 1.4986)
			(layers "F.Cu" "F.Mask" "F.Paste")
			(net "M_A_CPU1_SB_DQ<0>")
		)
		(pad "101" smd rect
			(at -2.050034 26.774902 270)
			(size 0.519938 1.4986)
			(layers "F.Cu" "F.Mask" "F.Paste")
			(net "GND")
		)
		(pad "102" smd rect
			(at -2.050034 27.62504 270)
			(size 0.519938 1.4986)
			(layers "F.Cu" "F.Mask" "F.Paste")
			(net "M_A_CPU1_SB_DQ<1>")
		)
		(pad "103" smd rect
			(at -2.050034 28.474924 270)
			(size 0.519938 1.4986)
			(layers "F.Cu" "F.Mask" "F.Paste")
			(net "GND")
		)
		(pad "104" smd rect
			(at -2.050034 29.325062 270)
			(size 0.519938 1.4986)
			(layers "F.Cu" "F.Mask" "F.Paste")
			(net "M_A_CPU1_SB_DQS_DP<0>")
		)
		(pad "105" smd rect
			(at -2.050034 30.174946 270)
			(size 0.519938 1.4986)
			(layers "F.Cu" "F.Mask" "F.Paste")
			(net "M_A_CPU1_SB_DQS_DN<0>")
		)
		(pad "106" smd rect
			(at -2.050034 31.025084 270)
			(size 0.519938 1.4986)
			(layers "F.Cu" "F.Mask" "F.Paste")
			(net "GND")
		)
		(pad "107" smd rect
			(at -2.050034 31.874968 270)
			(size 0.519938 1.4986)
			(layers "F.Cu" "F.Mask" "F.Paste")
			(net "M_A_CPU1_SB_DQ<4>")
		)
		(pad "108" smd rect
			(at -2.050034 32.725106 270)
			(size 0.519938 1.4986)
			(layers "F.Cu" "F.Mask" "F.Paste")
			(net "GND")
		)
		(pad "109" smd rect
			(at -2.050034 33.57499 270)
			(size 0.519938 1.4986)
			(layers "F.Cu" "F.Mask" "F.Paste")
			(net "M_A_CPU1_SB_DQ<5>")
		)
		(pad "110" smd rect
			(at -2.050034 34.425128 270)
			(size 0.519938 1.4986)
			(layers "F.Cu" "F.Mask" "F.Paste")
			(net "GND")
		)
		(pad "111" smd rect
			(at -2.050034 35.275012 270)
			(size 0.519938 1.4986)
			(layers "F.Cu" "F.Mask" "F.Paste")
			(net "M_A_CPU1_SB_DQ<8>")
		)
		(pad "112" smd rect
			(at -2.050034 36.124896 270)
			(size 0.519938 1.4986)
			(layers "F.Cu" "F.Mask" "F.Paste")
			(net "GND")
		)
	)
)
